# S9S_MB_2U (Grand Teton) — schematic netlist excerpt (pin names and nets, part order shuffled) for the footprints in the layout excerpt that follows; sources: Cadence DE-HDL packaged netlist, KiCad conversion of 03242023_DA0F0TMBIJ0_F0T_Motherboard_J_brd_V01_OCP.brd

C1171  Q_CAP  10UF 16V 10% EMPTY  pkg C0805  page 260 : A = P5V_AUX ; B = GND
R3554  Q_RES  33.2 1% CHIP  pkg 0402LF  page 170 : A = SMB_LM75_3_3V3AUX_SDA ; B = SMB_LM75_3_3V3AUX_SDA_R1
C842  Q_CAP_DIFFBUS  DIFF BUS_0.22UF 6.3V 20% X6S  pkg C0201  page 174 : \1\ = P5E_CPU0_PE1_TX_C_DN<13> ; \2\ = P5E_CPU0_PE1_TX_DN<13>

(kicad_pcb
	(version 20260206)
	(generator "pcbnew")
	(generator_version "10.0")
	(general
		(thickness 1.6)
		(legacy_teardrops no)
	)
	(paper "A4")
	(title_block
		(title "03242023_DA0F0TMBIJ0_F0T_Motherboard_J_brd_V01_OCP.brd")
		(comment 1 "Grand Teton / footprints 2399-2401 of 6105")
	)
	(layers
		(0 "F.Cu" signal "TOP")
		(4 "In1.Cu" signal "GND")
		(6 "In2.Cu" signal "IN1")
		(8 "In3.Cu" signal "GND1")
		(10 "In4.Cu" signal "IN2")
		(12 "In5.Cu" signal "GND2")
		(14 "In6.Cu" signal "IN3")
		(16 "In7.Cu" signal "GND3")
		(18 "In8.Cu" signal "VCC")
		(20 "In9.Cu" signal "VCC1")
		(22 "In10.Cu" signal "GND4")
		(24 "In11.Cu" signal "IN4")
		(26 "In12.Cu" signal "GND5")
		(28 "In13.Cu" signal "IN5")
		(30 "In14.Cu" signal "GND6")
		(32 "In15.Cu" signal "IN6")
		(34 "In16.Cu" signal "GND7")
		(2 "B.Cu" signal "BOTTOM")
		(9 "F.Adhes" user "F.Adhesive")
		(11 "B.Adhes" user "B.Adhesive")
		(13 "F.Paste" user "Package Geometry/Pastemask Top")
		(15 "B.Paste" user "Package Geometry/Pastemask Bottom")
		(5 "F.SilkS" user "Ref Des/Silkscreen Top")
		(7 "B.SilkS" user "Ref Des/Silkscreen Bottom")
		(1 "F.Mask" user "Board Geometry/Soldermask Top")
		(3 "B.Mask" user "Board Geometry/Soldermask Bottom")
		(17 "Dwgs.User" user "User.Drawings")
		(19 "Cmts.User" user "User.Comments")
		(21 "Eco1.User" user "User.Eco1")
		(23 "Eco2.User" user "User.Eco2")
		(25 "Edge.Cuts" user "Board Geometry/Outline")
		(27 "Margin" user)
		(31 "F.CrtYd" user "Package Geometry/Place Bound Top")
		(29 "B.CrtYd" user "Package Geometry/Place Bound Bottom")
		(35 "F.Fab" user "Ref Des/Assembly Top")
		(33 "B.Fab" user "Ref Des/Assembly Bottom")
	)
	(footprint ""
		(layer "F.Cu")
		(at 446.18783 -376.471434)
		(property "Reference" "C1171"
			(at 0 0 0)
			(layer "F.SilkS")
			(hide yes)
			(effects
				(font
					(size 1.27 1.27)
				)
			)
		)
		(property "Value" ""
			(at 0 0 0)
			(layer "F.Fab")
			(effects
				(font
					(size 1.27 1.27)
				)
			)
		)
		(duplicate_pad_numbers_are_jumpers no)
		(fp_line
			(start -1.524 -0.762)
			(end 1.524 -0.762)
			(stroke
				(width 0.1524)
				(type default)
			)
			(layer "F.SilkS")
		)
		(fp_line
			(start -1.524 0.762)
			(end -1.524 -0.762)
			(stroke
				(width 0.1524)
				(type default)
			)
			(layer "F.SilkS")
		)
		(fp_line
			(start 1.524 -0.762)
			(end 1.524 0.762)
			(stroke
				(width 0.1524)
				(type default)
			)
			(layer "F.SilkS")
		)
		(fp_line
			(start 1.524 0.762)
			(end -1.524 0.762)
			(stroke
				(width 0.1524)
				(type default)
			)
			(layer "F.SilkS")
		)
		(fp_line
			(start -1.1049 -0.724916)
			(end -1.1049 0.724916)
			(stroke
				(width 0.1)
				(type default)
			)
			(layer "F.Fab")
		)
		(fp_line
			(start -1.1049 0.724916)
			(end 1.1049 0.724916)
			(stroke
				(width 0.1)
				(type default)
			)
			(layer "F.Fab")
		)
		(fp_line
			(start 1.1049 -0.724916)
			(end -1.1049 -0.724916)
			(stroke
				(width 0.1)
				(type default)
			)
			(layer "F.Fab")
		)
		(fp_line
			(start 1.1049 0.724916)
			(end 1.1049 -0.724916)
			(stroke
				(width 0.1)
				(type default)
			)
			(layer "F.Fab")
		)
		(pad "1" smd rect
			(at -0.889 0 180)
			(size 1.016 1.27)
			(layers "F.Cu" "F.Mask" "F.Paste")
			(net "P5V_AUX")
		)
		(pad "2" smd rect
			(at 0.889 0 180)
			(size 1.016 1.27)
			(layers "F.Cu" "F.Mask" "F.Paste")
			(net "GND")
		)
	)
	(footprint ""
		(layer "F.Cu")
		(at 396.518384 -16.088614 90)
		(property "Reference" "C842"
			(at 0 0 90)
			(layer "F.SilkS")
			(hide yes)
			(effects
				(font
					(size 1.27 1.27)
				)
			)
		)
		(property "Value" ""
			(at 0 0 90)
			(layer "F.Fab")
			(effects
				(font
					(size 1.27 1.27)
				)
			)
		)
		(duplicate_pad_numbers_are_jumpers no)
		(fp_line
			(start 0.299974 -0.150114)
			(end 0.299974 0.150114)
			(stroke
				(width 0.1)
				(type default)
			)
			(layer "F.Fab")
		)
		(fp_line
			(start -0.299974 -0.150114)
			(end 0.299974 -0.150114)
			(stroke
				(width 0.1)
				(type default)
			)
			(layer "F.Fab")
		)
		(fp_line
			(start 0.299974 0.150114)
			(end -0.299974 0.150114)
			(stroke
				(width 0.1)
				(type default)
			)
			(layer "F.Fab")
		)
		(fp_line
			(start -0.299974 0.150114)
			(end -0.299974 -0.150114)
			(stroke
				(width 0.1)
				(type default)
			)
			(layer "F.Fab")
		)
		(pad "1" smd rect
			(at -0.2667 0 90)
			(size 0.3048 0.381)
			(layers "F.Cu" "F.Mask" "F.Paste")
			(net "P5E_CPU0_PE1_TX_C_DN<13>")
		)
		(pad "2" smd rect
			(at 0.2667 0 90)
			(size 0.3048 0.381)
			(layers "F.Cu" "F.Mask" "F.Paste")
			(net "P5E_CPU0_PE1_TX_DN<13>")
		)
	)
	(footprint ""
		(layer "F.Cu")
		(at 107.019598 -17.13611)
		(property "Reference" "R3554"
			(at 0 0 0)
			(layer "F.SilkS")
			(hide yes)
			(effects
				(font
					(size 1.27 1.27)
				)
			)
		)
		(property "Value" ""
			(at 0 0 0)
			(layer "F.Fab")
			(effects
				(font
					(size 1.27 1.27)
				)
			)
		)
		(duplicate_pad_numbers_are_jumpers no)
		(fp_line
			(start -0.7874 -0.4064)
			(end 0.7874 -0.4064)
			(stroke
				(width 0.1524)
				(type default)
			)
			(layer "F.SilkS")
		)
		(fp_line
			(start -0.7874 0.4064)
			(end -0.7874 -0.4064)
			(stroke
				(width 0.1524)
				(type default)
			)
			(layer "F.SilkS")
		)
		(fp_line
			(start 0.7874 -0.4064)
			(end 0.7874 0.4064)
			(stroke
				(width 0.1524)
				(type default)
			)
			(layer "F.SilkS")
		)
		(fp_line
			(start 0.7874 0.4064)
			(end -0.7874 0.4064)
			(stroke
				(width 0.1524)
				(type default)
			)
			(layer "F.SilkS")
		)
		(fp_line
			(start -0.67945 -0.305054)
			(end -0.12065 -0.305054)
			(stroke
				(width 0.1)
				(type default)
			)
			(layer "F.Fab")
		)
		(fp_line
			(start -0.67945 0.3048)
			(end -0.67945 -0.305054)
			(stroke
				(width 0.1)
				(type default)
			)
			(layer "F.Fab")
		)
		(fp_line
			(start -0.12065 -0.305054)
			(end -0.12065 -0.2794)
			(stroke
				(width 0.1)
				(type default)
			)
			(layer "F.Fab")
		)
		(fp_line
			(start -0.12065 -0.2794)
			(end 0.12065 -0.2794)
			(stroke
				(width 0.1)
				(type default)
			)
			(layer "F.Fab")
		)
		(fp_line
			(start -0.12065 0.2794)
			(end -0.12065 0.3048)
			(stroke
				(width 0.1)
				(type default)
			)
			(layer "F.Fab")
		)
		(fp_line
			(start -0.12065 0.3048)
			(end -0.67945 0.3048)
			(stroke
				(width 0.1)
				(type default)
			)
			(layer "F.Fab")
		)
		(fp_line
			(start 0.120396 0.2794)
			(end -0.12065 0.2794)
			(stroke
				(width 0.1)
				(type default)
			)
			(layer "F.Fab")
		)
		(fp_line
			(start 0.120396 0.3048)
			(end 0.120396 0.2794)
			(stroke
				(width 0.1)
				(type default)
			)
			(layer "F.Fab")
		)
		(fp_line
			(start 0.12065 -0.3048)
			(end 0.67945 -0.3048)
			(stroke
				(width 0.1)
				(type default)
			)
			(layer "F.Fab")
		)
		(fp_line
			(start 0.12065 -0.2794)
			(end 0.12065 -0.3048)
			(stroke
				(width 0.1)
				(type default)
			)
			(layer "F.Fab")
		)
		(fp_line
			(start 0.67945 -0.3048)
			(end 0.67945 0.3048)
			(stroke
				(width 0.1)
				(type default)
			)
			(layer "F.Fab")
		)
		(fp_line
			(start 0.67945 0.3048)
			(end 0.120396 0.3048)
			(stroke
				(width 0.1)
				(type default)
			)
			(layer "F.Fab")
		)
		(pad "1" smd circle
			(at -0.40005 0)
			(size 0 0)
			(layers "F.Cu" "F.Mask" "F.Paste")
			(net "SMB_LM75_3_3V3AUX_SDA")
		)
		(pad "2" smd circle
			(at 0.40005 0)
			(size 0 0)
			(layers "F.Cu" "F.Mask" "F.Paste")
			(net "SMB_LM75_3_3V3AUX_SDA_R1")
		)
	)
)
